(kicad_pcb
	(version 20241229)
	(generator "pcbnew")
	(generator_version "9.0")
	(general
		(thickness 1.599998)
		(legacy_teardrops no)
	)
	(paper "A4")
	(title_block
		(title "Artix - Datacenter Secure Control Module (DC-SCM)")
		(date "2024-11-06")
		(rev "1.1.3")
		(comment 9 "footprints 512-516 of 544")
	)
	(layers
		(0 "F.Cu" signal)
		(4 "In1.Cu" signal)
		(6 "In2.Cu" signal)
		(8 "In3.Cu" signal)
		(10 "In4.Cu" signal)
		(12 "In5.Cu" signal)
		(14 "In6.Cu" signal)
		(2 "B.Cu" signal)
		(9 "F.Adhes" user "F.Adhesive")
		(11 "B.Adhes" user "B.Adhesive")
		(13 "F.Paste" user)
		(15 "B.Paste" user)
		(5 "F.SilkS" user "F.Silkscreen")
		(7 "B.SilkS" user "B.Silkscreen")
		(1 "F.Mask" user)
		(3 "B.Mask" user)
		(17 "Dwgs.User" user "User.Drawings")
		(19 "Cmts.User" user "User.Comments")
		(21 "Eco1.User" user "User.Eco1")
		(23 "Eco2.User" user "User.Eco2")
		(25 "Edge.Cuts" user)
		(27 "Margin" user)
		(31 "F.CrtYd" user "F.Courtyard")
		(29 "B.CrtYd" user "B.Courtyard")
		(35 "F.Fab" user)
		(33 "B.Fab" user)
	)
	(footprint "antmicro-footprints:C_0201"
		(layer "B.Cu")
		(at 102.275 120.675)
		(descr "Capacitor SMD 0201")
		(tags "capacitor SMD 0201")
		(property "Reference" "C165"
			(at -20.575 0.625 0)
			(layer "B.SilkS")
			(effects
				(font
					(size 0.7 0.7)
					(thickness 0.15)
				)
				(justify right bottom mirror)
			)
		)
		(property "Value" "C_470n_0201"
			(at 0 -1.4 0)
			(layer "B.Fab")
			(effects
				(font
					(size 0.7 0.7)
					(thickness 0.15)
				)
				(justify right bottom mirror)
			)
		)
		(property "Datasheet" "https://product.tdk.com/en/search/capacitor/ceramic/mlcc/info?part_no=C0603X5R1A474M030BC"
			(at 0 0 0)
			(layer "F.Fab")
			(hide yes)
			(effects
				(font
					(size 1.27 1.27)
					(thickness 0.15)
				)
			)
		)
		(property "Description" "SMD Multilayer Ceramic Capacitor, 0.47 µF, 10 V, 0201 [0603 Metric], ± 20%, X5R, C"
			(at 0 0 0)
			(layer "F.Fab")
			(hide yes)
			(effects
				(font
					(size 1.27 1.27)
					(thickness 0.15)
				)
			)
		)
		(property "Author" "Antmicro"
			(at 0 0 0)
			(layer "B.Fab")
			(hide yes)
			(effects
				(font
					(size 1 1)
					(thickness 0.15)
				)
				(justify mirror)
			)
		)
		(property "Dielectric" ""
			(at 0 0 0)
			(layer "B.Fab")
			(hide yes)
			(effects
				(font
					(size 1 1)
					(thickness 0.15)
				)
				(justify mirror)
			)
		)
		(property "License" "Apache-2.0"
			(at 0 0 0)
			(layer "B.Fab")
			(hide yes)
			(effects
				(font
					(size 1 1)
					(thickness 0.15)
				)
				(justify mirror)
			)
		)
		(property "MPN" "C0603X5R1A474M030BC"
			(at 0 0 0)
			(layer "B.Fab")
			(hide yes)
			(effects
				(font
					(size 1 1)
					(thickness 0.15)
				)
				(justify mirror)
			)
		)
		(property "Manufacturer" "TDK"
			(at 0 0 0)
			(layer "B.Fab")
			(hide yes)
			(effects
				(font
					(size 1 1)
					(thickness 0.15)
				)
				(justify mirror)
			)
		)
		(property "Public" "False"
			(at 0 0 0)
			(layer "B.Fab")
			(hide yes)
			(effects
				(font
					(size 1 1)
					(thickness 0.15)
				)
				(justify mirror)
			)
		)
		(property "Val" "470n"
			(at 0 0 0)
			(layer "B.Fab")
			(hide yes)
			(effects
				(font
					(size 1 1)
					(thickness 0.15)
				)
				(justify mirror)
			)
		)
		(property "Voltage" ""
			(at 0 0 0)
			(layer "B.Fab")
			(hide yes)
			(effects
				(font
					(size 1 1)
					(thickness 0.15)
				)
				(justify mirror)
			)
		)
		(property "DNP" ""
			(at 0 0 0)
			(unlocked yes)
			(layer "B.Fab")
			(hide yes)
			(effects
				(font
					(size 1 1)
					(thickness 0.15)
				)
				(justify mirror)
			)
		)
		(sheetname "/FPGA power supply/")
		(sheetfile "fpga-power-supply.kicad_sch")
		(attr smd)
		(fp_rect
			(start -0.7 0.35)
			(end 0.7 -0.35)
			(stroke
				(width 0.05)
				(type default)
			)
			(fill no)
			(layer "B.CrtYd")
		)
		(fp_rect
			(start 0.3 -0.15)
			(end -0.301 0.149)
			(stroke
				(width 0.15)
				(type solid)
			)
			(fill no)
			(layer "B.Fab")
		)
		(pad "" smd roundrect
			(at -0.349 0.002)
			(size 0.318 0.36)
			(layers "B.Paste")
			(roundrect_rratio 0.25)
		)
		(pad "" smd roundrect
			(at 0.341 0.002)
			(size 0.318 0.36)
			(layers "B.Paste")
			(roundrect_rratio 0.25)
		)
		(pad "1" smd roundrect
			(at -0.321 0.002)
			(size 0.46 0.4)
			(layers "B.Cu" "B.Mask")
			(roundrect_rratio 0.25)
			(net 1 "GND")
			(pintype "passive")
		)
		(pad "2" smd roundrect
			(at 0.32 0.002)
			(size 0.46 0.4)
			(layers "B.Cu" "B.Mask")
			(roundrect_rratio 0.25)
			(net 6 "VCC1V0")
			(pintype "passive")
		)
	)
	(footprint "antmicro-footprints:C_0201"
		(layer "B.Cu")
		(at 104.325 120.675)
		(descr "Capacitor SMD 0201")
		(tags "capacitor SMD 0201")
		(property "Reference" "C242"
			(at -19.725 0.625 0)
			(layer "B.SilkS")
			(effects
				(font
					(size 0.7 0.7)
					(thickness 0.15)
				)
				(justify right bottom mirror)
			)
		)
		(property "Value" "C_470n_0201"
			(at 0 -1.4 0)
			(layer "B.Fab")
			(effects
				(font
					(size 0.7 0.7)
					(thickness 0.15)
				)
				(justify right bottom mirror)
			)
		)
		(property "Datasheet" "https://product.tdk.com/en/search/capacitor/ceramic/mlcc/info?part_no=C0603X5R1A474M030BC"
			(at 0 0 0)
			(layer "F.Fab")
			(hide yes)
			(effects
				(font
					(size 1.27 1.27)
					(thickness 0.15)
				)
			)
		)
		(property "Description" "SMD Multilayer Ceramic Capacitor, 0.47 µF, 10 V, 0201 [0603 Metric], ± 20%, X5R, C"
			(at 0 0 0)
			(layer "F.Fab")
			(hide yes)
			(effects
				(font
					(size 1.27 1.27)
					(thickness 0.15)
				)
			)
		)
		(property "Author" "Antmicro"
			(at 0 0 0)
			(layer "B.Fab")
			(hide yes)
			(effects
				(font
					(size 1 1)
					(thickness 0.15)
				)
				(justify mirror)
			)
		)
		(property "Dielectric" ""
			(at 0 0 0)
			(layer "B.Fab")
			(hide yes)
			(effects
				(font
					(size 1 1)
					(thickness 0.15)
				)
				(justify mirror)
			)
		)
		(property "License" "Apache-2.0"
			(at 0 0 0)
			(layer "B.Fab")
			(hide yes)
			(effects
				(font
					(size 1 1)
					(thickness 0.15)
				)
				(justify mirror)
			)
		)
		(property "MPN" "C0603X5R1A474M030BC"
			(at 0 0 0)
			(layer "B.Fab")
			(hide yes)
			(effects
				(font
					(size 1 1)
					(thickness 0.15)
				)
				(justify mirror)
			)
		)
		(property "Manufacturer" "TDK"
			(at 0 0 0)
			(layer "B.Fab")
			(hide yes)
			(effects
				(font
					(size 1 1)
					(thickness 0.15)
				)
				(justify mirror)
			)
		)
		(property "Public" "False"
			(at 0 0 0)
			(layer "B.Fab")
			(hide yes)
			(effects
				(font
					(size 1 1)
					(thickness 0.15)
				)
				(justify mirror)
			)
		)
		(property "Val" "470n"
			(at 0 0 0)
			(layer "B.Fab")
			(hide yes)
			(effects
				(font
					(size 1 1)
					(thickness 0.15)
				)
				(justify mirror)
			)
		)
		(property "Voltage" ""
			(at 0 0 0)
			(layer "B.Fab")
			(hide yes)
			(effects
				(font
					(size 1 1)
					(thickness 0.15)
				)
				(justify mirror)
			)
		)
		(sheetname "/FPGA power supply/")
		(sheetfile "fpga-power-supply.kicad_sch")
		(attr smd)
		(fp_rect
			(start -0.7 0.35)
			(end 0.7 -0.35)
			(stroke
				(width 0.05)
				(type default)
			)
			(fill no)
			(layer "B.CrtYd")
		)
		(fp_rect
			(start 0.3 -0.15)
			(end -0.301 0.149)
			(stroke
				(width 0.15)
				(type solid)
			)
			(fill no)
			(layer "B.Fab")
		)
		(pad "" smd roundrect
			(at -0.349 0.002)
			(size 0.318 0.36)
			(layers "B.Paste")
			(roundrect_rratio 0.25)
		)
		(pad "" smd roundrect
			(at 0.341 0.002)
			(size 0.318 0.36)
			(layers "B.Paste")
			(roundrect_rratio 0.25)
		)
		(pad "1" smd roundrect
			(at -0.321 0.002)
			(size 0.46 0.4)
			(layers "B.Cu" "B.Mask")
			(roundrect_rratio 0.25)
			(net 1 "GND")
			(pintype "passive")
		)
		(pad "2" smd roundrect
			(at 0.32 0.002)
			(size 0.46 0.4)
			(layers "B.Cu" "B.Mask")
			(roundrect_rratio 0.25)
			(net 5 "VCC1V8")
			(pintype "passive")
		)
	)
	(footprint "antmicro-footprints:C_0402_1005Metric"
		(layer "B.Cu")
		(at 123.355 129.665 -90)
		(descr "Capacitor SMD 0402")
		(tags "capacitor SMD 0402")
		(property "Reference" "C177"
			(at 0.835 -0.385 90)
			(layer "B.SilkS")
			(effects
				(font
					(size 0.7 0.7)
					(thickness 0.15)
				)
				(justify left bottom mirror)
			)
		)
		(property "Value" "C_4u7_0402"
			(at 0 -1.4 90)
			(layer "B.Fab")
			(effects
				(font
					(size 0.7 0.7)
					(thickness 0.15)
				)
				(justify left bottom mirror)
			)
		)
		(property "Datasheet" "https://www.murata.com/products/productdetail?partno=GRM155R61A475MEAA%23"
			(at 0 0 270)
			(layer "F.Fab")
			(hide yes)
			(effects
				(font
					(size 1.27 1.27)
					(thickness 0.15)
				)
			)
		)
		(property "Description" "SMD Multilayer Ceramic Capacitor, 4.7 µF, 10 V, 0402 [1005 Metric], ± 20%, X5R, GRM Series"
			(at 0 0 270)
			(layer "F.Fab")
			(hide yes)
			(effects
				(font
					(size 1.27 1.27)
					(thickness 0.15)
				)
			)
		)
		(property "Author" "Antmicro"
			(at -6.31 253.02 0)
			(layer "B.Fab")
			(hide yes)
			(effects
				(font
					(size 1 1)
					(thickness 0.15)
				)
				(justify mirror)
			)
		)
		(property "Dielectric" ""
			(at -6.31 253.02 0)
			(layer "B.Fab")
			(hide yes)
			(effects
				(font
					(size 1 1)
					(thickness 0.15)
				)
				(justify mirror)
			)
		)
		(property "License" "Apache-2.0"
			(at -6.31 253.02 0)
			(layer "B.Fab")
			(hide yes)
			(effects
				(font
					(size 1 1)
					(thickness 0.15)
				)
				(justify mirror)
			)
		)
		(property "MPN" "GRM155R61A475MEAAD"
			(at -6.31 253.02 0)
			(layer "B.Fab")
			(hide yes)
			(effects
				(font
					(size 1 1)
					(thickness 0.15)
				)
				(justify mirror)
			)
		)
		(property "Manufacturer" "Murata"
			(at -6.31 253.02 0)
			(layer "B.Fab")
			(hide yes)
			(effects
				(font
					(size 1 1)
					(thickness 0.15)
				)
				(justify mirror)
			)
		)
		(property "Val" "4u7"
			(at -6.31 253.02 0)
			(layer "B.Fab")
			(hide yes)
			(effects
				(font
					(size 1 1)
					(thickness 0.15)
				)
				(justify mirror)
			)
		)
		(property "Voltage" ""
			(at -6.31 253.02 0)
			(layer "B.Fab")
			(hide yes)
			(effects
				(font
					(size 1 1)
					(thickness 0.15)
				)
				(justify mirror)
			)
		)
		(sheetname "/Interfaces/")
		(sheetfile "interfaces.kicad_sch")
		(attr smd)
		(fp_rect
			(start -0.925 0.47)
			(end 0.925 -0.47)
			(stroke
				(width 0.05)
				(type default)
			)
			(fill no)
			(layer "B.CrtYd")
		)
		(fp_line
			(start -0.494 0.25)
			(end 0.504 0.25)
			(stroke
				(width 0.15)
				(type solid)
			)
			(layer "B.Fab")
		)
		(fp_line
			(start 0.504 0.25)
			(end 0.504 -0.248)
			(stroke
				(width 0.15)
				(type solid)
			)
			(layer "B.Fab")
		)
		(fp_line
			(start -0.494 -0.248)
			(end -0.494 0.25)
			(stroke
				(width 0.15)
				(type solid)
			)
			(layer "B.Fab")
		)
		(fp_line
			(start 0.504 -0.248)
			(end -0.494 -0.248)
			(stroke
				(width 0.15)
				(type solid)
			)
			(layer "B.Fab")
		)
		(pad "1" smd roundrect
			(at -0.48 0 270)
			(size 0.59 0.64)
			(layers "B.Cu" "B.Mask" "B.Paste")
			(roundrect_rratio 0.25)
			(net 1 "GND")
			(pintype "passive")
		)
		(pad "2" smd roundrect
			(at 0.48 0 270)
			(size 0.59 0.64)
			(layers "B.Cu" "B.Mask" "B.Paste")
			(roundrect_rratio 0.25)
			(net 108 "Net-(C177-Pad2)")
			(pintype "passive")
		)
	)
	(footprint "antmicro-footprints:C_0402_1005Metric"
		(layer "B.Cu")
		(at 126.415 129.665 -90)
		(descr "Capacitor SMD 0402")
		(tags "capacitor SMD 0402")
		(property "Reference" "C245"
			(at 0.835 -0.385 90)
			(layer "B.SilkS")
			(effects
				(font
					(size 0.7 0.7)
					(thickness 0.15)
				)
				(justify left bottom mirror)
			)
		)
		(property "Value" "C_4u7_0402"
			(at 0 -1.4 90)
			(layer "B.Fab")
			(effects
				(font
					(size 0.7 0.7)
					(thickness 0.15)
				)
				(justify left bottom mirror)
			)
		)
		(property "Datasheet" "https://www.murata.com/products/productdetail?partno=GRM155R61A475MEAA%23"
			(at 0 0 270)
			(layer "F.Fab")
			(hide yes)
			(effects
				(font
					(size 1.27 1.27)
					(thickness 0.15)
				)
			)
		)
		(property "Description" "SMD Multilayer Ceramic Capacitor, 4.7 µF, 10 V, 0402 [1005 Metric], ± 20%, X5R, GRM Series"
			(at 0 0 270)
			(layer "F.Fab")
			(hide yes)
			(effects
				(font
					(size 1.27 1.27)
					(thickness 0.15)
				)
			)
		)
		(property "Author" "Antmicro"
			(at -3.25 256.08 0)
			(layer "B.Fab")
			(hide yes)
			(effects
				(font
					(size 1 1)
					(thickness 0.15)
				)
				(justify mirror)
			)
		)
		(property "Dielectric" ""
			(at -3.25 256.08 0)
			(layer "B.Fab")
			(hide yes)
			(effects
				(font
					(size 1 1)
					(thickness 0.15)
				)
				(justify mirror)
			)
		)
		(property "License" "Apache-2.0"
			(at -3.25 256.08 0)
			(layer "B.Fab")
			(hide yes)
			(effects
				(font
					(size 1 1)
					(thickness 0.15)
				)
				(justify mirror)
			)
		)
		(property "MPN" "GRM155R61A475MEAAD"
			(at -3.25 256.08 0)
			(layer "B.Fab")
			(hide yes)
			(effects
				(font
					(size 1 1)
					(thickness 0.15)
				)
				(justify mirror)
			)
		)
		(property "Manufacturer" "Murata"
			(at -3.25 256.08 0)
			(layer "B.Fab")
			(hide yes)
			(effects
				(font
					(size 1 1)
					(thickness 0.15)
				)
				(justify mirror)
			)
		)
		(property "Val" "4u7"
			(at -3.25 256.08 0)
			(layer "B.Fab")
			(hide yes)
			(effects
				(font
					(size 1 1)
					(thickness 0.15)
				)
				(justify mirror)
			)
		)
		(property "Voltage" ""
			(at -3.25 256.08 0)
			(layer "B.Fab")
			(hide yes)
			(effects
				(font
					(size 1 1)
					(thickness 0.15)
				)
				(justify mirror)
			)
		)
		(sheetname "/Interfaces/")
		(sheetfile "interfaces.kicad_sch")
		(attr smd)
		(fp_rect
			(start -0.925 0.47)
			(end 0.925 -0.47)
			(stroke
				(width 0.05)
				(type default)
			)
			(fill no)
			(layer "B.CrtYd")
		)
		(fp_line
			(start -0.494 0.25)
			(end 0.504 0.25)
			(stroke
				(width 0.15)
				(type solid)
			)
			(layer "B.Fab")
		)
		(fp_line
			(start 0.504 0.25)
			(end 0.504 -0.248)
			(stroke
				(width 0.15)
				(type solid)
			)
			(layer "B.Fab")
		)
		(fp_line
			(start -0.494 -0.248)
			(end -0.494 0.25)
			(stroke
				(width 0.15)
				(type solid)
			)
			(layer "B.Fab")
		)
		(fp_line
			(start 0.504 -0.248)
			(end -0.494 -0.248)
			(stroke
				(width 0.15)
				(type solid)
			)
			(layer "B.Fab")
		)
		(pad "1" smd roundrect
			(at -0.48 0 270)
			(size 0.59 0.64)
			(layers "B.Cu" "B.Mask" "B.Paste")
			(roundrect_rratio 0.25)
			(net 1 "GND")
			(pintype "passive")
		)
		(pad "2" smd roundrect
			(at 0.48 0 270)
			(size 0.59 0.64)
			(layers "B.Cu" "B.Mask" "B.Paste")
			(roundrect_rratio 0.25)
			(net 11 "Net-(U18-VDDA1.8)")
			(pintype "passive")
		)
	)
	(footprint "antmicro-footprints:C_0402_1005Metric"
		(layer "B.Cu")
		(at 125.92875 113.465 -90)
		(descr "Capacitor SMD 0402")
		(tags "capacitor SMD 0402")
		(property "Reference" "C246"
			(at 0.825 -0.31375 90)
			(layer "B.SilkS")
			(effects
				(font
					(size 0.7 0.7)
					(thickness 0.15)
				)
				(justify left bottom mirror)
			)
		)
		(property "Value" "C_4u7_0402"
			(at 0 -1.4 90)
			(layer "B.Fab")
			(effects
				(font
					(size 0.7 0.7)
					(thickness 0.15)
				)
				(justify left bottom mirror)
			)
		)
		(property "Datasheet" "https://www.murata.com/products/productdetail?partno=GRM155R61A475MEAA%23"
			(at 0 0 270)
			(layer "F.Fab")
			(hide yes)
			(effects
				(font
					(size 1.27 1.27)
					(thickness 0.15)
				)
			)
		)
		(property "Description" "SMD Multilayer Ceramic Capacitor, 4.7 µF, 10 V, 0402 [1005 Metric], ± 20%, X5R, GRM Series"
			(at 0 0 270)
			(layer "F.Fab")
			(hide yes)
			(effects
				(font
					(size 1.27 1.27)
					(thickness 0.15)
				)
			)
		)
		(property "Author" "Antmicro"
			(at 12.46375 239.39375 0)
			(layer "B.Fab")
			(hide yes)
			(effects
				(font
					(size 1 1)
					(thickness 0.15)
				)
				(justify mirror)
			)
		)
		(property "Dielectric" ""
			(at 12.46375 239.39375 0)
			(layer "B.Fab")
			(hide yes)
			(effects
				(font
					(size 1 1)
					(thickness 0.15)
				)
				(justify mirror)
			)
		)
		(property "License" "Apache-2.0"
			(at 12.46375 239.39375 0)
			(layer "B.Fab")
			(hide yes)
			(effects
				(font
					(size 1 1)
					(thickness 0.15)
				)
				(justify mirror)
			)
		)
		(property "MPN" "GRM155R61A475MEAAD"
			(at 12.46375 239.39375 0)
			(layer "B.Fab")
			(hide yes)
			(effects
				(font
					(size 1 1)
					(thickness 0.15)
				)
				(justify mirror)
			)
		)
		(property "Manufacturer" "Murata"
			(at 12.46375 239.39375 0)
			(layer "B.Fab")
			(hide yes)
			(effects
				(font
					(size 1 1)
					(thickness 0.15)
				)
				(justify mirror)
			)
		)
		(property "Val" "4u7"
			(at 12.46375 239.39375 0)
			(layer "B.Fab")
			(hide yes)
			(effects
				(font
					(size 1 1)
					(thickness 0.15)
				)
				(justify mirror)
			)
		)
		(property "Voltage" ""
			(at 12.46375 239.39375 0)
			(layer "B.Fab")
			(hide yes)
			(effects
				(font
					(size 1 1)
					(thickness 0.15)
				)
				(justify mirror)
			)
		)
		(sheetname "/Interfaces/")
		(sheetfile "interfaces.kicad_sch")
		(attr smd)
		(fp_rect
			(start -0.925 0.47)
			(end 0.925 -0.47)
			(stroke
				(width 0.05)
				(type default)
			)
			(fill no)
			(layer "B.CrtYd")
		)
		(fp_line
			(start -0.494 0.25)
			(end 0.504 0.25)
			(stroke
				(width 0.15)
				(type solid)
			)
			(layer "B.Fab")
		)
		(fp_line
			(start 0.504 0.25)
			(end 0.504 -0.248)
			(stroke
				(width 0.15)
				(type solid)
			)
			(layer "B.Fab")
		)
		(fp_line
			(start -0.494 -0.248)
			(end -0.494 0.25)
			(stroke
				(width 0.15)
				(type solid)
			)
			(layer "B.Fab")
		)
		(fp_line
			(start 0.504 -0.248)
			(end -0.494 -0.248)
			(stroke
				(width 0.15)
				(type solid)
			)
			(layer "B.Fab")
		)
		(pad "1" smd roundrect
			(at -0.48 0 270)
			(size 0.59 0.64)
			(layers "B.Cu" "B.Mask" "B.Paste")
			(roundrect_rratio 0.25)
			(net 1 "GND")
			(pintype "passive")
		)
		(pad "2" smd roundrect
			(at 0.48 0 270)
			(size 0.59 0.64)
			(layers "B.Cu" "B.Mask" "B.Paste")
			(roundrect_rratio 0.25)
			(net 12 "Net-(U17-VDDA1.8)")
			(pintype "passive")
		)
	)
)
